(kicad_pcb
	(version 20260206)
	(generator "pcbnew")
	(generator_version "10.0")
	(general
		(thickness 1.6)
		(legacy_teardrops no)
	)
	(paper "A4")
	(title_block
		(title "Wiwynn_Tioga_Pass_MB.brd")
		(comment 1 "Tioga Pass / footprints 376-383 of 4770")
	)
	(layers
		(0 "F.Cu" signal "TOP")
		(4 "In1.Cu" signal "L2GND")
		(6 "In2.Cu" signal "L3")
		(8 "In3.Cu" signal "L4GND")
		(10 "In4.Cu" signal "L5")
		(12 "In5.Cu" signal "L6GND")
		(14 "In6.Cu" signal "L7VCC")
		(16 "In7.Cu" signal "L8VCC")
		(18 "In8.Cu" signal "L9GND")
		(20 "In9.Cu" signal "L10")
		(22 "In10.Cu" signal "L11GND")
		(24 "In11.Cu" signal "L12")
		(26 "In12.Cu" signal "L13GND")
		(2 "B.Cu" signal "BOTTOM")
		(9 "F.Adhes" user "F.Adhesive")
		(11 "B.Adhes" user "B.Adhesive")
		(13 "F.Paste" user "Package Geometry/Pastemask Top")
		(15 "B.Paste" user "Package Geometry/Pastemask Bottom")
		(5 "F.SilkS" user "Ref Des/Silkscreen Top")
		(7 "B.SilkS" user "Ref Des/Silkscreen Bottom")
		(1 "F.Mask" user "Board Geometry/Soldermask Top")
		(3 "B.Mask" user "Board Geometry/Soldermask Bottom")
		(17 "Dwgs.User" user "User.Drawings")
		(19 "Cmts.User" user "User.Comments")
		(21 "Eco1.User" user "User.Eco1")
		(23 "Eco2.User" user "User.Eco2")
		(25 "Edge.Cuts" user "Board Geometry/Outline")
		(27 "Margin" user)
		(31 "F.CrtYd" user "Package Geometry/Place Bound Top")
		(29 "B.CrtYd" user "Package Geometry/Place Bound Bottom")
		(35 "F.Fab" user "Ref Des/Assembly Top")
		(33 "B.Fab" user "Ref Des/Assembly Bottom")
	)
	(footprint ""
		(layer "F.Cu")
		(at 436.794402 -0.821182 -90)
		(property "Reference" "R8D21"
			(at 0 0 270)
			(layer "F.SilkS")
			(hide yes)
			(effects
				(font
					(size 1.27 1.27)
				)
			)
		)
		(property "Value" ""
			(at 0 0 270)
			(layer "F.Fab")
			(effects
				(font
					(size 1.27 1.27)
				)
			)
		)
		(duplicate_pad_numbers_are_jumpers no)
		(fp_poly
			(pts
				(xy -0.2794 -0.1016) (xy 0.2794 -0.1016) (xy 0.2794 0.9906) (xy -0.2794 0.9906)
			)
			(stroke
				(width 0)
				(type default)
			)
			(fill no)
			(layer "F.CrtYd")
		)
		(fp_line
			(start -0.2794 0.9906)
			(end 0.2794 0.9906)
			(stroke
				(width 0.1)
				(type default)
			)
			(layer "F.Fab")
		)
		(fp_line
			(start 0.2794 0.9906)
			(end 0.2794 -0.1016)
			(stroke
				(width 0.1)
				(type default)
			)
			(layer "F.Fab")
		)
		(fp_line
			(start -0.2794 -0.1016)
			(end -0.2794 0.9906)
			(stroke
				(width 0.1)
				(type default)
			)
			(layer "F.Fab")
		)
		(fp_line
			(start 0.2794 -0.1016)
			(end -0.2794 -0.1016)
			(stroke
				(width 0.1)
				(type default)
			)
			(layer "F.Fab")
		)
		(pad "1" smd rect
			(at 0 0 270)
			(size 0.508 0.508)
			(layers "F.Cu" "F.Mask" "F.Paste")
			(net "P3V3_STBY")
		)
		(pad "2" smd rect
			(at 0 0.889 270)
			(size 0.508 0.508)
			(layers "F.Cu" "F.Mask" "F.Paste")
			(net "FM_IE_DISABLE_N")
		)
		(zone
			(layer "F.Cu")
			(hatch none 0.5)
			(connect_pads
				(clearance 0)
			)
			(min_thickness 0.25)
			(keepout
				(tracks not_allowed)
				(vias allowed)
				(pads allowed)
				(copperpour not_allowed)
				(footprints allowed)
			)
			(placement
				(enabled no)
				(sheetname "")
			)
			(fill
				(thermal_gap 0.5)
				(thermal_bridge_width 0.5)
				(island_removal_mode 0)
			)
			(polygon
				(pts
					(xy 436.159402 -1.075182) (xy 436.159402 -0.567182) (xy 436.540402 -0.567182) (xy 436.540402 -1.075182)
				)
			)
		)
		(zone
			(layer "F.Cu")
			(hatch none 0.5)
			(connect_pads
				(clearance 0)
			)
			(min_thickness 0.25)
			(keepout
				(tracks allowed)
				(vias not_allowed)
				(pads allowed)
				(copperpour not_allowed)
				(footprints allowed)
			)
			(placement
				(enabled no)
				(sheetname "")
			)
			(fill
				(thermal_gap 0.5)
				(thermal_bridge_width 0.5)
				(island_removal_mode 0)
			)
			(polygon
				(pts
					(xy 436.540402 -1.075182) (xy 436.540402 -0.567182) (xy 436.159402 -0.567182) (xy 436.159402 -1.075182)
				)
			)
		)
	)
	(footprint ""
		(layer "F.Cu")
		(at 401.7518 -54.80558 -90)
		(property "Reference" "R7F4"
			(at 0 0 270)
			(layer "F.SilkS")
			(hide yes)
			(effects
				(font
					(size 1.27 1.27)
				)
			)
		)
		(property "Value" ""
			(at 0 0 270)
			(layer "F.Fab")
			(effects
				(font
					(size 1.27 1.27)
				)
			)
		)
		(duplicate_pad_numbers_are_jumpers no)
		(fp_poly
			(pts
				(xy -0.2794 -0.1016) (xy 0.2794 -0.1016) (xy 0.2794 0.9906) (xy -0.2794 0.9906)
			)
			(stroke
				(width 0)
				(type default)
			)
			(fill no)
			(layer "F.CrtYd")
		)
		(fp_line
			(start -0.2794 0.9906)
			(end 0.2794 0.9906)
			(stroke
				(width 0.1)
				(type default)
			)
			(layer "F.Fab")
		)
		(fp_line
			(start 0.2794 0.9906)
			(end 0.2794 -0.1016)
			(stroke
				(width 0.1)
				(type default)
			)
			(layer "F.Fab")
		)
		(fp_line
			(start -0.2794 -0.1016)
			(end -0.2794 0.9906)
			(stroke
				(width 0.1)
				(type default)
			)
			(layer "F.Fab")
		)
		(fp_line
			(start 0.2794 -0.1016)
			(end -0.2794 -0.1016)
			(stroke
				(width 0.1)
				(type default)
			)
			(layer "F.Fab")
		)
		(pad "1" smd rect
			(at 0 0 270)
			(size 0.508 0.508)
			(layers "F.Cu" "F.Mask" "F.Paste")
			(net "SPI_SWITCH_MISO")
		)
		(pad "2" smd rect
			(at 0 0.889 270)
			(size 0.508 0.508)
			(layers "F.Cu" "F.Mask" "F.Paste")
			(net "SPI_MISO_R0")
		)
		(zone
			(layer "F.Cu")
			(hatch none 0.5)
			(connect_pads
				(clearance 0)
			)
			(min_thickness 0.25)
			(keepout
				(tracks not_allowed)
				(vias allowed)
				(pads allowed)
				(copperpour not_allowed)
				(footprints allowed)
			)
			(placement
				(enabled no)
				(sheetname "")
			)
			(fill
				(thermal_gap 0.5)
				(thermal_bridge_width 0.5)
				(island_removal_mode 0)
			)
			(polygon
				(pts
					(xy 401.1168 -55.05958) (xy 401.1168 -54.55158) (xy 401.4978 -54.55158) (xy 401.4978 -55.05958)
				)
			)
		)
		(zone
			(layer "F.Cu")
			(hatch none 0.5)
			(connect_pads
				(clearance 0)
			)
			(min_thickness 0.25)
			(keepout
				(tracks allowed)
				(vias not_allowed)
				(pads allowed)
				(copperpour not_allowed)
				(footprints allowed)
			)
			(placement
				(enabled no)
				(sheetname "")
			)
			(fill
				(thermal_gap 0.5)
				(thermal_bridge_width 0.5)
				(island_removal_mode 0)
			)
			(polygon
				(pts
					(xy 401.4978 -55.05958) (xy 401.4978 -54.55158) (xy 401.1168 -54.55158) (xy 401.1168 -55.05958)
				)
			)
		)
	)
	(footprint ""
		(layer "F.Cu")
		(at 8.026146 -3.659886 -90)
		(property "Reference" "C1G16"
			(at 0 0 270)
			(layer "F.SilkS")
			(hide yes)
			(effects
				(font
					(size 1.27 1.27)
				)
			)
		)
		(property "Value" ""
			(at 0 0 270)
			(layer "F.Fab")
			(effects
				(font
					(size 1.27 1.27)
				)
			)
		)
		(duplicate_pad_numbers_are_jumpers no)
		(fp_rect
			(start -0.3048 0.9906)
			(end 0.3048 -0.1016)
			(stroke
				(width 0)
				(type default)
			)
			(fill no)
			(layer "F.CrtYd")
		)
		(fp_line
			(start -0.3048 0.9906)
			(end 0.3048 0.9906)
			(stroke
				(width 0.1)
				(type default)
			)
			(layer "F.Fab")
		)
		(fp_line
			(start 0.3048 0.9906)
			(end 0.3048 -0.1016)
			(stroke
				(width 0.1)
				(type default)
			)
			(layer "F.Fab")
		)
		(fp_line
			(start -0.3048 -0.1016)
			(end -0.3048 0.9906)
			(stroke
				(width 0.1)
				(type default)
			)
			(layer "F.Fab")
		)
		(fp_line
			(start 0.3048 -0.1016)
			(end -0.3048 -0.1016)
			(stroke
				(width 0.1)
				(type default)
			)
			(layer "F.Fab")
		)
		(pad "1" smd rect
			(at 0 0 270)
			(size 0.508 0.508)
			(layers "F.Cu" "F.Mask" "F.Paste")
			(net "VR_PVDDQ_GHJ_AVSP")
		)
		(pad "2" smd rect
			(at 0 0.889 270)
			(size 0.508 0.508)
			(layers "F.Cu" "F.Mask" "F.Paste")
			(net "VSENSE_PVDDQ_GHJ_N")
		)
		(zone
			(layer "F.Cu")
			(hatch none 0.5)
			(connect_pads
				(clearance 0)
			)
			(min_thickness 0.25)
			(keepout
				(tracks allowed)
				(vias not_allowed)
				(pads allowed)
				(copperpour not_allowed)
				(footprints allowed)
			)
			(placement
				(enabled no)
				(sheetname "")
			)
			(fill
				(thermal_gap 0.5)
				(thermal_bridge_width 0.5)
				(island_removal_mode 0)
			)
			(polygon
				(pts
					(xy 7.391146 -3.913886) (xy 7.391146 -3.405886) (xy 7.772146 -3.405886) (xy 7.772146 -3.913886)
				)
			)
		)
		(zone
			(layer "F.Cu")
			(hatch none 0.5)
			(connect_pads
				(clearance 0)
			)
			(min_thickness 0.25)
			(keepout
				(tracks not_allowed)
				(vias allowed)
				(pads allowed)
				(copperpour not_allowed)
				(footprints allowed)
			)
			(placement
				(enabled no)
				(sheetname "")
			)
			(fill
				(thermal_gap 0.5)
				(thermal_bridge_width 0.5)
				(island_removal_mode 0)
			)
			(polygon
				(pts
					(xy 7.391146 -3.913886) (xy 7.391146 -3.405886) (xy 7.772146 -3.405886) (xy 7.772146 -3.913886)
				)
			)
		)
	)
	(footprint ""
		(layer "F.Cu")
		(at 267.2588 -84.7598)
		(property "Reference" "C5D8"
			(at 0 0 0)
			(layer "F.SilkS")
			(hide yes)
			(effects
				(font
					(size 1.27 1.27)
				)
			)
		)
		(property "Value" ""
			(at 0 0 0)
			(layer "F.Fab")
			(effects
				(font
					(size 1.27 1.27)
				)
			)
		)
		(duplicate_pad_numbers_are_jumpers no)
		(fp_poly
			(pts
				(xy -0.4953 -0.2032) (xy 0.4953 -0.2032) (xy 0.4953 1.6002) (xy -0.4953 1.6002)
			)
			(stroke
				(width 0)
				(type default)
			)
			(fill no)
			(layer "F.CrtYd")
		)
		(fp_line
			(start -0.4953 -0.2032)
			(end 0.4953 -0.2032)
			(stroke
				(width 0.1)
				(type default)
			)
			(layer "F.Fab")
		)
		(fp_line
			(start -0.4953 1.6002)
			(end -0.4953 -0.2032)
			(stroke
				(width 0.1)
				(type default)
			)
			(layer "F.Fab")
		)
		(fp_line
			(start 0.4953 -0.2032)
			(end 0.4953 1.6002)
			(stroke
				(width 0.1)
				(type default)
			)
			(layer "F.Fab")
		)
		(fp_line
			(start 0.4953 1.6002)
			(end -0.4953 1.6002)
			(stroke
				(width 0.1)
				(type default)
			)
			(layer "F.Fab")
		)
		(pad "1" smd rect
			(at 0 0)
			(size 0.762 0.889)
			(layers "F.Cu" "F.Mask" "F.Paste")
			(net "PVDDQ_DEF")
		)
		(pad "2" smd rect
			(at 0 1.397)
			(size 0.762 0.889)
			(layers "F.Cu" "F.Mask" "F.Paste")
			(net "GND")
		)
		(zone
			(layer "F.Cu")
			(hatch none 0.5)
			(connect_pads
				(clearance 0)
			)
			(min_thickness 0.25)
			(keepout
				(tracks not_allowed)
				(vias allowed)
				(pads allowed)
				(copperpour not_allowed)
				(footprints allowed)
			)
			(placement
				(enabled no)
				(sheetname "")
			)
			(fill
				(thermal_gap 0.5)
				(thermal_bridge_width 0.5)
				(island_removal_mode 0)
			)
			(polygon
				(pts
					(xy 266.8778 -84.3153) (xy 267.6398 -84.3153) (xy 267.6398 -83.8073) (xy 266.8778 -83.8073)
				)
			)
		)
	)
	(footprint ""
		(layer "F.Cu")
		(at 20.9423 -83.312 90)
		(property "Reference" "U1D2"
			(at 1.1684 -0.90043 90)
			(unlocked yes)
			(layer "F.SilkS")
			(effects
				(font
					(size 0.7874 0.5842)
					(thickness 0.1524)
				)
			)
		)
		(property "Value" ""
			(at 0 0 90)
			(layer "F.Fab")
			(effects
				(font
					(size 1.27 1.27)
				)
			)
		)
		(duplicate_pad_numbers_are_jumpers no)
		(fp_circle
			(center -1.0795 -0.054102)
			(end -1.0795 0.072898)
			(stroke
				(width 0.254)
				(type default)
			)
			(fill no)
			(layer "F.SilkS")
		)
		(fp_rect
			(start -0.216154 1.27508)
			(end 1.333754 -0.275082)
			(stroke
				(width 0)
				(type default)
			)
			(fill no)
			(layer "F.CrtYd")
		)
		(fp_line
			(start 1.333754 -0.275082)
			(end 1.333754 1.27508)
			(stroke
				(width 0.1)
				(type default)
			)
			(layer "F.Fab")
		)
		(fp_line
			(start -0.216154 -0.275082)
			(end 1.333754 -0.275082)
			(stroke
				(width 0.1)
				(type default)
			)
			(layer "F.Fab")
		)
		(fp_line
			(start 1.333754 1.27508)
			(end -0.216154 1.27508)
			(stroke
				(width 0.1)
				(type default)
			)
			(layer "F.Fab")
		)
		(fp_line
			(start -0.216154 1.27508)
			(end -0.216154 -0.275082)
			(stroke
				(width 0.1)
				(type default)
			)
			(layer "F.Fab")
		)
		(fp_circle
			(center -1.0795 -0.054102)
			(end -1.0795 0.072898)
			(stroke
				(width 0.635)
				(type default)
			)
			(fill no)
			(layer "F.Fab")
		)
		(pad "1" smd rect
			(at 0 0 90)
			(size 0.9398 0.3048)
			(layers "F.Cu" "F.Mask" "F.Paste")
			(net "IRQ_OC_DETECT_N")
		)
		(pad "2" smd rect
			(at -0.0254 0.500126 90)
			(size 0.889 0.3048)
			(layers "F.Cu" "F.Mask" "F.Paste")
			(net "P12V_STBY")
		)
		(pad "3" smd rect
			(at -0.0254 0.999998 90)
			(size 0.889 0.3048)
			(layers "F.Cu" "F.Mask" "F.Paste")
			(net "A_HSC_HIGH")
		)
		(pad "4" smd rect
			(at 1.143 0.999998 90)
			(size 0.889 0.3048)
			(layers "F.Cu" "F.Mask" "F.Paste")
			(net "A_HSC_LOW")
		)
		(pad "5" smd rect
			(at 1.143 0.500126 90)
			(size 0.889 0.3048)
			(layers "F.Cu" "F.Mask" "F.Paste")
			(net "GND")
		)
		(pad "6" smd rect
			(at 1.143 0 90)
			(size 0.889 0.3048)
			(layers "F.Cu" "F.Mask" "F.Paste")
			(net "A_HSC_LOW_GATE")
		)
	)
	(footprint ""
		(layer "F.Cu")
		(at 398.030192 -10.917936)
		(property "Reference" "C7G25"
			(at 0 0 0)
			(layer "F.SilkS")
			(hide yes)
			(effects
				(font
					(size 1.27 1.27)
				)
			)
		)
		(property "Value" ""
			(at 0 0 0)
			(layer "F.Fab")
			(effects
				(font
					(size 1.27 1.27)
				)
			)
		)
		(duplicate_pad_numbers_are_jumpers no)
		(fp_rect
			(start -0.3048 0.9906)
			(end 0.3048 -0.1016)
			(stroke
				(width 0)
				(type default)
			)
			(fill no)
			(layer "F.CrtYd")
		)
		(fp_line
			(start -0.3048 -0.1016)
			(end -0.3048 0.9906)
			(stroke
				(width 0.1)
				(type default)
			)
			(layer "F.Fab")
		)
		(fp_line
			(start -0.3048 0.9906)
			(end 0.3048 0.9906)
			(stroke
				(width 0.1)
				(type default)
			)
			(layer "F.Fab")
		)
		(fp_line
			(start 0.3048 -0.1016)
			(end -0.3048 -0.1016)
			(stroke
				(width 0.1)
				(type default)
			)
			(layer "F.Fab")
		)
		(fp_line
			(start 0.3048 0.9906)
			(end 0.3048 -0.1016)
			(stroke
				(width 0.1)
				(type default)
			)
			(layer "F.Fab")
		)
		(pad "1" smd rect
			(at 0 0)
			(size 0.508 0.508)
			(layers "F.Cu" "F.Mask" "F.Paste")
			(net "P3E_CPU0_PE2_SS_TXP<5>")
		)
		(pad "2" smd rect
			(at 0 0.889)
			(size 0.508 0.508)
			(layers "F.Cu" "F.Mask" "F.Paste")
			(net "P3E_CPU0_PE2_SS_C_TXP<5>")
		)
		(zone
			(layer "F.Cu")
			(hatch none 0.5)
			(connect_pads
				(clearance 0)
			)
			(min_thickness 0.25)
			(keepout
				(tracks not_allowed)
				(vias allowed)
				(pads allowed)
				(copperpour not_allowed)
				(footprints allowed)
			)
			(placement
				(enabled no)
				(sheetname "")
			)
			(fill
				(thermal_gap 0.5)
				(thermal_bridge_width 0.5)
				(island_removal_mode 0)
			)
			(polygon
				(pts
					(xy 397.776192 -10.282936) (xy 398.284192 -10.282936) (xy 398.284192 -10.663936) (xy 397.776192 -10.663936)
				)
			)
		)
		(zone
			(layer "F.Cu")
			(hatch none 0.5)
			(connect_pads
				(clearance 0)
			)
			(min_thickness 0.25)
			(keepout
				(tracks allowed)
				(vias not_allowed)
				(pads allowed)
				(copperpour not_allowed)
				(footprints allowed)
			)
			(placement
				(enabled no)
				(sheetname "")
			)
			(fill
				(thermal_gap 0.5)
				(thermal_bridge_width 0.5)
				(island_removal_mode 0)
			)
			(polygon
				(pts
					(xy 397.776192 -10.282936) (xy 398.284192 -10.282936) (xy 398.284192 -10.663936) (xy 397.776192 -10.663936)
				)
			)
		)
	)
	(footprint ""
		(layer "F.Cu")
		(at 433.9336 -18.533872 -90)
		(property "Reference" "C10W4"
			(at -0.8382 -0.67818 270)
			(unlocked yes)
			(layer "F.SilkS")
			(effects
				(font
					(size 0.4064 0.254)
					(thickness 0.1524)
				)
				(justify left)
			)
		)
		(property "Value" ""
			(at 0 0 270)
			(layer "F.Fab")
			(effects
				(font
					(size 1.27 1.27)
				)
			)
		)
		(duplicate_pad_numbers_are_jumpers no)
		(fp_poly
			(pts
				(xy 0.3048 -0.1016) (xy 0.3048 0.9906) (xy -0.3048 0.9906) (xy -0.3048 -0.1016)
			)
			(stroke
				(width 0)
				(type default)
			)
			(fill no)
			(layer "F.CrtYd")
		)
		(fp_line
			(start -0.3048 0.9906)
			(end 0.3048 0.9906)
			(stroke
				(width 0.1)
				(type default)
			)
			(layer "F.Fab")
		)
		(fp_line
			(start 0.3048 0.9906)
			(end 0.3048 -0.1016)
			(stroke
				(width 0.1)
				(type default)
			)
			(layer "F.Fab")
		)
		(fp_line
			(start -0.3048 -0.1016)
			(end -0.3048 0.9906)
			(stroke
				(width 0.1)
				(type default)
			)
			(layer "F.Fab")
		)
		(fp_line
			(start 0.3048 -0.1016)
			(end -0.3048 -0.1016)
			(stroke
				(width 0.1)
				(type default)
			)
			(layer "F.Fab")
		)
		(pad "1" smd rect
			(at 0 0 270)
			(size 0.508 0.508)
			(layers "F.Cu" "F.Mask" "F.Paste")
			(net "P3V3_STBY")
		)
		(pad "2" smd rect
			(at 0 0.889 270)
			(size 0.508 0.508)
			(layers "F.Cu" "F.Mask" "F.Paste")
			(net "GND")
		)
		(zone
			(layer "F.Cu")
			(hatch none 0.5)
			(connect_pads
				(clearance 0)
			)
			(min_thickness 0.25)
			(keepout
				(tracks not_allowed)
				(vias allowed)
				(pads allowed)
				(copperpour not_allowed)
				(footprints allowed)
			)
			(placement
				(enabled no)
				(sheetname "")
			)
			(fill
				(thermal_gap 0.5)
				(thermal_bridge_width 0.5)
				(island_removal_mode 0)
			)
			(polygon
				(pts
					(xy 433.2986 -18.787872) (xy 433.2986 -18.279872) (xy 433.6796 -18.279872) (xy 433.6796 -18.787872)
				)
			)
		)
		(zone
			(layer "F.Cu")
			(hatch none 0.5)
			(connect_pads
				(clearance 0)
			)
			(min_thickness 0.25)
			(keepout
				(tracks allowed)
				(vias not_allowed)
				(pads allowed)
				(copperpour not_allowed)
				(footprints allowed)
			)
			(placement
				(enabled no)
				(sheetname "")
			)
			(fill
				(thermal_gap 0.5)
				(thermal_bridge_width 0.5)
				(island_removal_mode 0)
			)
			(polygon
				(pts
					(xy 433.6796 -18.787872) (xy 433.6796 -18.279872) (xy 433.2986 -18.279872) (xy 433.2986 -18.787872)
				)
			)
		)
	)
	(footprint ""
		(layer "F.Cu")
		(at 396.5448 -0.2286)
		(property "Reference" "R8G16"
			(at 0 0 0)
			(layer "F.SilkS")
			(hide yes)
			(effects
				(font
					(size 1.27 1.27)
				)
			)
		)
		(property "Value" ""
			(at 0 0 0)
			(layer "F.Fab")
			(effects
				(font
					(size 1.27 1.27)
				)
			)
		)
		(duplicate_pad_numbers_are_jumpers no)
		(fp_poly
			(pts
				(xy -0.2794 -0.1016) (xy 0.2794 -0.1016) (xy 0.2794 0.9906) (xy -0.2794 0.9906)
			)
			(stroke
				(width 0)
				(type default)
			)
			(fill no)
			(layer "F.CrtYd")
		)
		(fp_line
			(start -0.2794 -0.1016)
			(end -0.2794 0.9906)
			(stroke
				(width 0.1)
				(type default)
			)
			(layer "F.Fab")
		)
		(fp_line
			(start -0.2794 0.9906)
			(end 0.2794 0.9906)
			(stroke
				(width 0.1)
				(type default)
			)
			(layer "F.Fab")
		)
		(fp_line
			(start 0.2794 -0.1016)
			(end -0.2794 -0.1016)
			(stroke
				(width 0.1)
				(type default)
			)
			(layer "F.Fab")
		)
		(fp_line
			(start 0.2794 0.9906)
			(end 0.2794 -0.1016)
			(stroke
				(width 0.1)
				(type default)
			)
			(layer "F.Fab")
		)
		(pad "1" smd rect
			(at 0 0)
			(size 0.508 0.508)
			(layers "F.Cu" "F.Mask" "F.Paste")
			(net "JTAG_PCH_PLD_TCK")
		)
		(pad "2" smd rect
			(at 0 0.889)
			(size 0.508 0.508)
			(layers "F.Cu" "F.Mask" "F.Paste")
			(net "JTAG_TCK")
		)
		(zone
			(layer "F.Cu")
			(hatch none 0.5)
			(connect_pads
				(clearance 0)
			)
			(min_thickness 0.25)
			(keepout
				(tracks allowed)
				(vias not_allowed)
				(pads allowed)
				(copperpour not_allowed)
				(footprints allowed)
			)
			(placement
				(enabled no)
				(sheetname "")
			)
			(fill
				(thermal_gap 0.5)
				(thermal_bridge_width 0.5)
				(island_removal_mode 0)
			)
			(polygon
				(pts
					(xy 396.2908 0.0254) (xy 396.7988 0.0254) (xy 396.7988 0.4064) (xy 396.2908 0.4064)
				)
			)
		)
		(zone
			(layer "F.Cu")
			(hatch none 0.5)
			(connect_pads
				(clearance 0)
			)
			(min_thickness 0.25)
			(keepout
				(tracks not_allowed)
				(vias allowed)
				(pads allowed)
				(copperpour not_allowed)
				(footprints allowed)
			)
			(placement
				(enabled no)
				(sheetname "")
			)
			(fill
				(thermal_gap 0.5)
				(thermal_bridge_width 0.5)
				(island_removal_mode 0)
			)
			(polygon
				(pts
					(xy 396.2908 0.4064) (xy 396.7988 0.4064) (xy 396.7988 0.0254) (xy 396.2908 0.0254)
				)
			)
		)
	)
)
